# TIMECARD (Time Appliance Project (Time Card)) — schematic netlist excerpt (pin names and nets, part order shuffled) for the footprints in the layout excerpt that follows; sources: Cadence DE-HDL packaged netlist, KiCad conversion of R4006-B0001-02_R01.brd

C284  CAPACITOR  22UF 10V 20%  pkg SMC_0805R_H057  page 33 : \1\ = UNNAMED_525_CAPACITOR_I7_1 ; \2\ = SG
TP188  TP_PIONT  pkg TP010CT020B030_PTH  page 25 : \1\ = IO_L24N_16

(kicad_pcb
	(version 20260206)
	(generator "pcbnew")
	(generator_version "10.0")
	(general
		(thickness 1.6)
		(legacy_teardrops no)
	)
	(paper "A4")
	(title_block
		(title "timecard-production-celestica-r4006 — R4006-B0001-02_R01.brd")
		(comment 1 "Time Appliance Project (Time Card) / footprints 621-622 of 1113")
	)
	(layers
		(0 "F.Cu" signal "TOP")
		(4 "In1.Cu" signal "L02_GND1")
		(6 "In2.Cu" signal "L03_SIG1")
		(8 "In3.Cu" signal "L04_GND2")
		(10 "In4.Cu" signal "L05_VCC1")
		(12 "In5.Cu" signal "L06_VCC2")
		(14 "In6.Cu" signal "L07_GND3")
		(16 "In7.Cu" signal "L08_SIG2")
		(18 "In8.Cu" signal "L09_GND4")
		(2 "B.Cu" signal "BOTTOM")
		(9 "F.Adhes" user "F.Adhesive")
		(11 "B.Adhes" user "B.Adhesive")
		(13 "F.Paste" user "Package Geometry/Pastemask Top")
		(15 "B.Paste" user "Package Geometry/Pastemask Bottom")
		(5 "F.SilkS" user "Ref Des/Silkscreen Top")
		(7 "B.SilkS" user "Ref Des/Silkscreen Bottom")
		(1 "F.Mask" user "Board Geometry/Soldermask Top")
		(3 "B.Mask" user "Board Geometry/Soldermask Bottom")
		(17 "Dwgs.User" user "User.Drawings")
		(19 "Cmts.User" user "User.Comments")
		(21 "Eco1.User" user "User.Eco1")
		(23 "Eco2.User" user "User.Eco2")
		(25 "Edge.Cuts" user "Board Geometry/Outline")
		(27 "Margin" user)
		(31 "F.CrtYd" user "Package Geometry/Place Bound Top")
		(29 "B.CrtYd" user "Package Geometry/Place Bound Bottom")
		(35 "F.Fab" user "Ref Des/Assembly Top")
		(33 "B.Fab" user "Ref Des/Assembly Bottom")
	)
	(footprint ""
		(layer "F.Cu")
		(at 108.0516 -58.3184)
		(property "Reference" "TP188"
			(at 2.85115 2.1082 90)
			(unlocked yes)
			(layer "F.SilkS")
			(effects
				(font
					(size 0.635 0.4064)
					(thickness 0.1524)
				)
				(justify left)
			)
		)
		(property "Value" ""
			(at 0 0 0)
			(layer "F.Fab")
			(effects
				(font
					(size 1.27 1.27)
				)
			)
		)
		(property "Device Type" "TP_PIONT-TP010CT020B030_PTH-TPA"
			(at -1.341882 0.996696 0)
			(unlocked yes)
			(layer "F.Fab")
			(hide yes)
			(effects
				(font
					(size 0.7874 0.5842)
					(thickness 0.1524)
				)
				(justify left)
			)
		)
		(duplicate_pad_numbers_are_jumpers no)
		(fp_poly
			(pts
				(arc
					(start 0.889 0)
					(mid -0.889 0)
					(end 0.889 0)
				)
			)
			(stroke
				(width 0)
				(type default)
			)
			(fill no)
			(layer "B.CrtYd")
		)
		(fp_poly
			(pts
				(arc
					(start 0.889 0)
					(mid -0.889 0)
					(end 0.889 0)
				)
			)
			(stroke
				(width 0)
				(type default)
			)
			(fill no)
			(layer "F.CrtYd")
		)
		(pad "1" thru_hole circle
			(at 0 0)
			(size 0.508 0.508)
			(drill 0.254)
			(layers "*.Cu" "*.Mask")
			(remove_unused_layers no)
			(net "IO_L24N_16")
			(clearance 0.1016)
			(padstack
				(mode front_inner_back)
				(layer "Inner"
					(shape circle)
					(size 0.508 0.508)
					(clearance 0.1016)
				)
				(layer "B.Cu"
					(shape circle)
					(size 0.762 0.762)
					(clearance -0.0254)
				)
			)
		)
	)
	(footprint ""
		(layer "F.Cu")
		(at 46.101 -82.804)
		(property "Reference" "C284"
			(at 0.127 -2.24663 0)
			(unlocked yes)
			(layer "F.SilkS")
			(effects
				(font
					(size 0.7874 0.5842)
					(thickness 0.1524)
				)
			)
		)
		(property "Value" "VAL*"
			(at 0.0762 3.134106 0)
			(unlocked yes)
			(layer "F.Fab")
			(hide yes)
			(effects
				(font
					(size 0.7874 0.5842)
					(thickness 0.1524)
				)
			)
		)
		(property "Tolerance" "TOL*"
			(at 0.0762 4.048506 0)
			(unlocked yes)
			(layer "Cmts.User")
			(hide yes)
			(effects
				(font
					(size 0.7874 0.5842)
					(thickness 0.1524)
				)
			)
		)
		(property "User Part Number" "PARTNUM*"
			(at 0.1016 5.013706 0)
			(unlocked yes)
			(layer "Cmts.User")
			(hide yes)
			(effects
				(font
					(size 0.7874 0.5842)
					(thickness 0.1524)
				)
			)
		)
		(property "Device Type" "CAPACITOR-G107-0F226-CM,22UF,2A"
			(at 0.0508 2.194306 0)
			(unlocked yes)
			(layer "F.Fab")
			(hide yes)
			(effects
				(font
					(size 0.7874 0.5842)
					(thickness 0.1524)
				)
			)
		)
		(duplicate_pad_numbers_are_jumpers no)
		(fp_line
			(start -1.5748 -0.9398)
			(end -1.5748 0.9398)
			(stroke
				(width 0.1)
				(type default)
			)
			(layer "F.SilkS")
		)
		(fp_line
			(start -1.5748 0.9398)
			(end 1.5748 0.9398)
			(stroke
				(width 0.1)
				(type default)
			)
			(layer "F.SilkS")
		)
		(fp_line
			(start 1.5748 -0.9398)
			(end -1.5748 -0.9398)
			(stroke
				(width 0.1)
				(type default)
			)
			(layer "F.SilkS")
		)
		(fp_line
			(start 1.5748 0.9398)
			(end 1.5748 -0.9398)
			(stroke
				(width 0.1)
				(type default)
			)
			(layer "F.SilkS")
		)
		(fp_poly
			(pts
				(xy -1.5748 0.9398) (xy 1.5748 0.9398) (xy 1.5748 -0.9398) (xy -1.5748 -0.9398)
			)
			(stroke
				(width 0)
				(type default)
			)
			(fill no)
			(layer "F.CrtYd")
		)
		(fp_line
			(start -1.016 -0.635)
			(end -1.016 0.635)
			(stroke
				(width 0.1)
				(type default)
			)
			(layer "F.Fab")
		)
		(fp_line
			(start -1.016 0.635)
			(end 1.016 0.635)
			(stroke
				(width 0.1)
				(type default)
			)
			(layer "F.Fab")
		)
		(fp_line
			(start 1.016 -0.635)
			(end -1.016 -0.635)
			(stroke
				(width 0.1)
				(type default)
			)
			(layer "F.Fab")
		)
		(fp_line
			(start 1.016 0.635)
			(end 1.016 -0.635)
			(stroke
				(width 0.1)
				(type default)
			)
			(layer "F.Fab")
		)
		(pad "1" smd rect
			(at -0.8382 0)
			(size 0.9652 1.3716)
			(layers "F.Cu" "F.Mask" "F.Paste")
			(net "UNNAMED_525_CAPACITOR_I7_1")
		)
		(pad "2" smd rect
			(at 0.8382 0)
			(size 0.9652 1.3716)
			(layers "F.Cu" "F.Mask" "F.Paste")
			(net "SG")
		)
		(zone
			(layer "F.Cu")
			(hatch none 0.5)
			(connect_pads
				(clearance 0)
			)
			(min_thickness 0.25)
			(keepout
				(tracks not_allowed)
				(vias allowed)
				(pads allowed)
				(copperpour not_allowed)
				(footprints allowed)
			)
			(placement
				(enabled no)
				(sheetname "")
			)
			(fill
				(thermal_gap 0.5)
				(thermal_bridge_width 0.5)
				(island_removal_mode 0)
			)
			(polygon
				(pts
					(xy 45.8724 -82.169) (xy 46.3296 -82.169) (xy 46.3296 -83.439) (xy 45.8724 -83.439)
				)
			)
		)
		(zone
			(layer "F.Cu")
			(hatch none 0.5)
			(connect_pads
				(clearance 0)
			)
			(min_thickness 0.25)
			(keepout
				(tracks allowed)
				(vias not_allowed)
				(pads allowed)
				(copperpour not_allowed)
				(footprints allowed)
			)
			(placement
				(enabled no)
				(sheetname "")
			)
			(fill
				(thermal_gap 0.5)
				(thermal_bridge_width 0.5)
				(island_removal_mode 0)
			)
			(polygon
				(pts
					(xy 45.8724 -82.169) (xy 46.3296 -82.169) (xy 46.3296 -83.439) (xy 45.8724 -83.439)
				)
			)
		)
	)
)
